# T6G (Grand Teton) — schematic netlist excerpt (pin names and nets, part order shuffled) for the footprints in the layout excerpt that follows; sources: Cadence DE-HDL packaged netlist, KiCad conversion of 04192023_DAF0TMB3IC0_F0TG_MB_C_brd_V02_OCP.brd

R1348  Q_RES  33.2 1% CHIP  pkg 0402LF  page 251 : A = SMB_INA230_3V3AUX_SCL ; B = SMB_INA230_8_3V3AUX_SCL_R
PC261_2  Q_CAP  0.1UF 25V 10% X7R  pkg 0402  page 211 : A = SW_P12V_AUX_PVDDCR_CPU0_P1_FLT ; B = GND

(kicad_pcb
	(version 20260206)
	(generator "pcbnew")
	(generator_version "10.0")
	(general
		(thickness 1.6)
		(legacy_teardrops no)
	)
	(paper "A4")
	(title_block
		(title "04192023_DAF0TMB3IC0_F0TG_MB_C_brd_V02_OCP.brd")
		(comment 1 "Grand Teton / footprints 3382-3384 of 8354")
	)
	(layers
		(0 "F.Cu" signal "TOP")
		(4 "In1.Cu" signal "GND")
		(6 "In2.Cu" signal "IN1")
		(8 "In3.Cu" signal "GND1")
		(10 "In4.Cu" signal "IN2")
		(12 "In5.Cu" signal "GND2")
		(14 "In6.Cu" signal "IN3")
		(16 "In7.Cu" signal "GND3")
		(18 "In8.Cu" signal "VCC")
		(20 "In9.Cu" signal "VCC1")
		(22 "In10.Cu" signal "GND4")
		(24 "In11.Cu" signal "IN4")
		(26 "In12.Cu" signal "GND5")
		(28 "In13.Cu" signal "IN5")
		(30 "In14.Cu" signal "GND6")
		(32 "In15.Cu" signal "IN6")
		(34 "In16.Cu" signal "GND7")
		(2 "B.Cu" signal "BOTTOM")
		(9 "F.Adhes" user "F.Adhesive")
		(11 "B.Adhes" user "B.Adhesive")
		(13 "F.Paste" user "Package Geometry/Pastemask Top")
		(15 "B.Paste" user "Package Geometry/Pastemask Bottom")
		(5 "F.SilkS" user "Ref Des/Silkscreen Top")
		(7 "B.SilkS" user "Ref Des/Silkscreen Bottom")
		(1 "F.Mask" user "Board Geometry/Soldermask Top")
		(3 "B.Mask" user "Board Geometry/Soldermask Bottom")
		(17 "Dwgs.User" user "User.Drawings")
		(19 "Cmts.User" user "User.Comments")
		(21 "Eco1.User" user "User.Eco1")
		(23 "Eco2.User" user "User.Eco2")
		(25 "Edge.Cuts" user "Board Geometry/Outline")
		(27 "Margin" user)
		(31 "F.CrtYd" user "Package Geometry/Place Bound Top")
		(29 "B.CrtYd" user "Package Geometry/Place Bound Bottom")
		(35 "F.Fab" user "Ref Des/Assembly Top")
		(33 "B.Fab" user "Ref Des/Assembly Bottom")
	)
	(footprint ""
		(layer "F.Cu")
		(at 297.688 -108.966 -90)
		(property "Reference" "R1348"
			(at 0 0 270)
			(layer "F.SilkS")
			(hide yes)
			(effects
				(font
					(size 1.27 1.27)
				)
			)
		)
		(property "Value" ""
			(at 0 0 270)
			(layer "F.Fab")
			(effects
				(font
					(size 1.27 1.27)
				)
			)
		)
		(duplicate_pad_numbers_are_jumpers no)
		(fp_line
			(start -0.7874 0.4064)
			(end -0.7874 -0.4064)
			(stroke
				(width 0.1524)
				(type default)
			)
			(layer "F.SilkS")
		)
		(fp_line
			(start 0.7874 0.4064)
			(end -0.7874 0.4064)
			(stroke
				(width 0.1524)
				(type default)
			)
			(layer "F.SilkS")
		)
		(fp_line
			(start -0.7874 -0.4064)
			(end 0.7874 -0.4064)
			(stroke
				(width 0.1524)
				(type default)
			)
			(layer "F.SilkS")
		)
		(fp_line
			(start 0.7874 -0.4064)
			(end 0.7874 0.4064)
			(stroke
				(width 0.1524)
				(type default)
			)
			(layer "F.SilkS")
		)
		(fp_line
			(start -0.67945 0.3048)
			(end -0.67945 -0.305054)
			(stroke
				(width 0.1)
				(type default)
			)
			(layer "F.Fab")
		)
		(fp_line
			(start -0.12065 0.3048)
			(end -0.67945 0.3048)
			(stroke
				(width 0.1)
				(type default)
			)
			(layer "F.Fab")
		)
		(fp_line
			(start 0.120396 0.3048)
			(end 0.120396 0.2794)
			(stroke
				(width 0.1)
				(type default)
			)
			(layer "F.Fab")
		)
		(fp_line
			(start 0.67945 0.3048)
			(end 0.120396 0.3048)
			(stroke
				(width 0.1)
				(type default)
			)
			(layer "F.Fab")
		)
		(fp_line
			(start -0.12065 0.2794)
			(end -0.12065 0.3048)
			(stroke
				(width 0.1)
				(type default)
			)
			(layer "F.Fab")
		)
		(fp_line
			(start 0.120396 0.2794)
			(end -0.12065 0.2794)
			(stroke
				(width 0.1)
				(type default)
			)
			(layer "F.Fab")
		)
		(fp_line
			(start -0.12065 -0.2794)
			(end 0.12065 -0.2794)
			(stroke
				(width 0.1)
				(type default)
			)
			(layer "F.Fab")
		)
		(fp_line
			(start 0.12065 -0.2794)
			(end 0.12065 -0.3048)
			(stroke
				(width 0.1)
				(type default)
			)
			(layer "F.Fab")
		)
		(fp_line
			(start 0.12065 -0.3048)
			(end 0.67945 -0.3048)
			(stroke
				(width 0.1)
				(type default)
			)
			(layer "F.Fab")
		)
		(fp_line
			(start 0.67945 -0.3048)
			(end 0.67945 0.3048)
			(stroke
				(width 0.1)
				(type default)
			)
			(layer "F.Fab")
		)
		(fp_line
			(start -0.67945 -0.305054)
			(end -0.12065 -0.305054)
			(stroke
				(width 0.1)
				(type default)
			)
			(layer "F.Fab")
		)
		(fp_line
			(start -0.12065 -0.305054)
			(end -0.12065 -0.2794)
			(stroke
				(width 0.1)
				(type default)
			)
			(layer "F.Fab")
		)
		(pad "1" smd circle
			(at -0.40005 0 270)
			(size 0 0)
			(layers "F.Cu" "F.Mask" "F.Paste")
			(net "SMB_INA230_3V3AUX_SCL")
		)
		(pad "2" smd circle
			(at 0.40005 0 270)
			(size 0 0)
			(layers "F.Cu" "F.Mask" "F.Paste")
			(net "SMB_INA230_8_3V3AUX_SCL_R")
		)
	)
	(footprint ""
		(layer "F.Cu")
		(at 103.951786 -104.674924 180)
		(property "Reference" ""
			(at 0 0 180)
			(layer "F.SilkS")
			(hide yes)
			(effects
				(font
					(size 1.27 1.27)
				)
			)
		)
		(property "Value" ""
			(at 0 0 180)
			(layer "F.Fab")
			(effects
				(font
					(size 1.27 1.27)
				)
			)
		)
		(duplicate_pad_numbers_are_jumpers no)
		(pad "1" smd circle
			(at 0 0 180)
			(size 0.9906 0.9906)
			(layers "F.Cu" "F.Mask" "F.Paste")
			(net "Net_2238")
		)
		(zone
			(layer "F.Cu")
			(hatch none 0.5)
			(connect_pads
				(clearance 0)
			)
			(min_thickness 0.25)
			(keepout
				(tracks not_allowed)
				(vias allowed)
				(pads allowed)
				(copperpour not_allowed)
				(footprints allowed)
			)
			(placement
				(enabled no)
				(sheetname "")
			)
			(fill
				(thermal_gap 0.5)
				(thermal_bridge_width 0.5)
				(island_removal_mode 0)
			)
			(polygon
				(pts
					(arc
						(start 105.577386 -104.674924)
						(mid 102.326186 -104.674924)
						(end 105.577386 -104.674924)
					)
				)
			)
		)
	)
	(footprint ""
		(layer "F.Cu")
		(at 86.420706 -178.359562 180)
		(property "Reference" "PC261_2"
			(at 0 0 180)
			(layer "F.SilkS")
			(hide yes)
			(effects
				(font
					(size 1.27 1.27)
				)
			)
		)
		(property "Value" ""
			(at 0 0 180)
			(layer "F.Fab")
			(effects
				(font
					(size 1.27 1.27)
				)
			)
		)
		(duplicate_pad_numbers_are_jumpers no)
		(fp_line
			(start 0.7874 0.4064)
			(end -0.7874 0.4064)
			(stroke
				(width 0.1524)
				(type default)
			)
			(layer "F.SilkS")
		)
		(fp_line
			(start 0.7874 -0.4064)
			(end 0.7874 0.4064)
			(stroke
				(width 0.1524)
				(type default)
			)
			(layer "F.SilkS")
		)
		(fp_line
			(start -0.7874 0.4064)
			(end -0.7874 -0.4064)
			(stroke
				(width 0.1524)
				(type default)
			)
			(layer "F.SilkS")
		)
		(fp_line
			(start -0.7874 -0.4064)
			(end 0.7874 -0.4064)
			(stroke
				(width 0.1524)
				(type default)
			)
			(layer "F.SilkS")
		)
		(fp_line
			(start 0.67945 0.3048)
			(end 0.120396 0.3048)
			(stroke
				(width 0.1)
				(type default)
			)
			(layer "F.Fab")
		)
		(fp_line
			(start 0.67945 -0.3048)
			(end 0.67945 0.3048)
			(stroke
				(width 0.1)
				(type default)
			)
			(layer "F.Fab")
		)
		(fp_line
			(start 0.12065 -0.2794)
			(end 0.12065 -0.3048)
			(stroke
				(width 0.1)
				(type default)
			)
			(layer "F.Fab")
		)
		(fp_line
			(start 0.12065 -0.3048)
			(end 0.67945 -0.3048)
			(stroke
				(width 0.1)
				(type default)
			)
			(layer "F.Fab")
		)
		(fp_line
			(start 0.120396 0.3048)
			(end 0.120396 0.2794)
			(stroke
				(width 0.1)
				(type default)
			)
			(layer "F.Fab")
		)
		(fp_line
			(start 0.120396 0.2794)
			(end -0.12065 0.2794)
			(stroke
				(width 0.1)
				(type default)
			)
			(layer "F.Fab")
		)
		(fp_line
			(start -0.12065 0.3048)
			(end -0.67945 0.3048)
			(stroke
				(width 0.1)
				(type default)
			)
			(layer "F.Fab")
		)
		(fp_line
			(start -0.12065 0.2794)
			(end -0.12065 0.3048)
			(stroke
				(width 0.1)
				(type default)
			)
			(layer "F.Fab")
		)
		(fp_line
			(start -0.12065 -0.2794)
			(end 0.12065 -0.2794)
			(stroke
				(width 0.1)
				(type default)
			)
			(layer "F.Fab")
		)
		(fp_line
			(start -0.12065 -0.305054)
			(end -0.12065 -0.2794)
			(stroke
				(width 0.1)
				(type default)
			)
			(layer "F.Fab")
		)
		(fp_line
			(start -0.67945 0.3048)
			(end -0.67945 -0.305054)
			(stroke
				(width 0.1)
				(type default)
			)
			(layer "F.Fab")
		)
		(fp_line
			(start -0.67945 -0.305054)
			(end -0.12065 -0.305054)
			(stroke
				(width 0.1)
				(type default)
			)
			(layer "F.Fab")
		)
		(pad "1" smd circle
			(at -0.40005 0 180)
			(size 0 0)
			(layers "F.Cu" "F.Mask" "F.Paste")
			(net "SW_P12V_AUX_PVDDCR_CPU0_P1_FLT")
		)
		(pad "2" smd circle
			(at 0.40005 0 180)
			(size 0 0)
			(layers "F.Cu" "F.Mask" "F.Paste")
			(net "GND")
		)
	)
)
